(kicad_pcb
	(version 20260206)
	(generator "pcbnew")
	(generator_version "10.0")
	(general
		(thickness 1.6)
		(legacy_teardrops no)
	)
	(paper "A4")
	(title_block
		(title "01162023_DA0F0TEBIF0_F0T_Expander_BD_F_brd_V02_OCP.brd")
		(comment 1 "Grand Teton / footprint 5622 of 9728 (PEX2), pads 714-835 of 2397")
	)
	(layers
		(0 "F.Cu" signal "TOP")
		(4 "In1.Cu" signal "GND")
		(6 "In2.Cu" signal "VCC")
		(8 "In3.Cu" signal "VCC1")
		(10 "In4.Cu" signal "GND1")
		(12 "In5.Cu" signal "IN1")
		(14 "In6.Cu" signal "GND2")
		(16 "In7.Cu" signal "IN2")
		(18 "In8.Cu" signal "GND3")
		(20 "In9.Cu" signal "IN3")
		(22 "In10.Cu" signal "GND4")
		(24 "In11.Cu" signal "IN4")
		(26 "In12.Cu" signal "GND5")
		(28 "In13.Cu" signal "IN5")
		(30 "In14.Cu" signal "GND6")
		(32 "In15.Cu" signal "IN6")
		(34 "In16.Cu" signal "GND7")
		(2 "B.Cu" signal "BOTTOM")
		(9 "F.Adhes" user "F.Adhesive")
		(11 "B.Adhes" user "B.Adhesive")
		(13 "F.Paste" user "Package Geometry/Pastemask Top")
		(15 "B.Paste" user "Package Geometry/Pastemask Bottom")
		(5 "F.SilkS" user "Ref Des/Silkscreen Top")
		(7 "B.SilkS" user "Ref Des/Silkscreen Bottom")
		(1 "F.Mask" user "Board Geometry/Soldermask Top")
		(3 "B.Mask" user "Board Geometry/Soldermask Bottom")
		(17 "Dwgs.User" user "User.Drawings")
		(19 "Cmts.User" user "User.Comments")
		(21 "Eco1.User" user "User.Eco1")
		(23 "Eco2.User" user "User.Eco2")
		(25 "Edge.Cuts" user "Board Geometry/Outline")
		(27 "Margin" user)
		(31 "F.CrtYd" user "Package Geometry/Place Bound Top")
		(29 "B.CrtYd" user "Package Geometry/Place Bound Bottom")
		(35 "F.Fab" user "Ref Des/Assembly Top")
		(33 "B.Fab" user "Ref Des/Assembly Bottom")
	)
	(footprint ""
		(layer "F.Cu")
		(at 291.84981 -295.89984)
		(property "Reference" "PEX2"
			(at -3.35153 35.56762 0)
			(unlocked yes)
			(layer "F.SilkS")
			(effects
				(font
					(size 2.032 1.524)
					(thickness 0.1524)
				)
				(justify left)
			)
		)
		(property "Value" ""
			(at 0 0 0)
			(layer "F.Fab")
			(effects
				(font
					(size 1.27 1.27)
				)
			)
		)
		(duplicate_pad_numbers_are_jumpers no)
		(pad "AP30" smd circle
			(at 4.750054 8.549894)
			(size 0.4572 0.4572)
			(layers "F.Cu" "F.Mask" "F.Paste")
			(net "P1V25_SERDES_VDDPLL_PEX2")
		)
		(pad "AP31" smd circle
			(at 5.700014 8.549894)
			(size 0.4572 0.4572)
			(layers "F.Cu" "F.Mask" "F.Paste")
			(net "P1V25_SERDES_VDDPLL_PEX2")
		)
		(pad "AP32" smd circle
			(at 6.649974 8.549894)
			(size 0.4572 0.4572)
			(layers "F.Cu" "F.Mask" "F.Paste")
			(net "P1V25_SERDES_VDDPLL_PEX2")
		)
		(pad "AP33" smd circle
			(at 7.599934 8.549894)
			(size 0.4572 0.4572)
			(layers "F.Cu" "F.Mask" "F.Paste")
			(net "P1V25_SERDES_VDDPLL_PEX2")
		)
		(pad "AP34" smd circle
			(at 8.549894 8.549894)
			(size 0.4572 0.4572)
			(layers "F.Cu" "F.Mask" "F.Paste")
			(net "GND")
		)
		(pad "AP35" smd circle
			(at 9.500108 8.549894)
			(size 0.4572 0.4572)
			(layers "F.Cu" "F.Mask" "F.Paste")
			(net "P1V8_VDDA_PEX2")
		)
		(pad "AP36" smd circle
			(at 10.450068 8.549894)
			(size 0.4572 0.4572)
			(layers "F.Cu" "F.Mask" "F.Paste")
			(net "Net_525")
		)
		(pad "AP37" smd circle
			(at 11.400028 8.549894)
			(size 0.4572 0.4572)
			(layers "F.Cu" "F.Mask" "F.Paste")
			(net "GND")
		)
		(pad "AP38" smd circle
			(at 12.349988 8.549894)
			(size 0.4572 0.4572)
			(layers "F.Cu" "F.Mask" "F.Paste")
			(net "Net_5380")
		)
		(pad "AP39" smd circle
			(at 13.299948 8.549894)
			(size 0.4572 0.4572)
			(layers "F.Cu" "F.Mask" "F.Paste")
			(net "Net_5386")
		)
		(pad "AP40" smd circle
			(at 14.249908 8.549894)
			(size 0.4572 0.4572)
			(layers "F.Cu" "F.Mask" "F.Paste")
			(net "GND")
		)
		(pad "AP41" smd circle
			(at 15.200122 8.549894)
			(size 0.4572 0.4572)
			(layers "F.Cu" "F.Mask" "F.Paste")
			(net "P5E_PEX2_STN0_TX_DP<1>")
		)
		(pad "AP42" smd circle
			(at 16.150082 8.549894)
			(size 0.4572 0.4572)
			(layers "F.Cu" "F.Mask" "F.Paste")
			(net "P5E_PEX2_STN0_TX_DN<1>")
		)
		(pad "AP43" smd circle
			(at 17.100042 8.549894)
			(size 0.4572 0.4572)
			(layers "F.Cu" "F.Mask" "F.Paste")
			(net "GND")
		)
		(pad "AP44" smd circle
			(at 18.050002 8.549894)
			(size 0.4572 0.4572)
			(layers "F.Cu" "F.Mask" "F.Paste")
			(net "GND")
		)
		(pad "AP45" smd circle
			(at 18.999962 8.549894)
			(size 0.4572 0.4572)
			(layers "F.Cu" "F.Mask" "F.Paste")
			(net "GND")
		)
		(pad "AP46" smd circle
			(at 19.949922 8.549894)
			(size 0.4572 0.4572)
			(layers "F.Cu" "F.Mask" "F.Paste")
			(net "GND")
		)
		(pad "AP47" smd circle
			(at 20.899882 8.549894)
			(size 0.4572 0.4572)
			(layers "F.Cu" "F.Mask" "F.Paste")
			(net "GND")
		)
		(pad "AP48" smd circle
			(at 21.850096 8.549894)
			(size 0.4572 0.4572)
			(layers "F.Cu" "F.Mask" "F.Paste")
			(net "P5E_PEX2_STN0_RX_DP<1>")
		)
		(pad "AP49" smd circle
			(at 22.800056 8.549894)
			(size 0.4572 0.4572)
			(layers "F.Cu" "F.Mask" "F.Paste")
			(net "P5E_PEX2_STN0_RX_DN<1>")
		)
		(pad "AR1" smd circle
			(at -22.800056 9.500108)
			(size 0.4572 0.4572)
			(layers "F.Cu" "F.Mask" "F.Paste")
			(net "GND")
		)
		(pad "AR2" smd circle
			(at -21.850096 9.500108)
			(size 0.4572 0.4572)
			(layers "F.Cu" "F.Mask" "F.Paste")
			(net "GND")
		)
		(pad "AR3" smd circle
			(at -20.899882 9.500108)
			(size 0.4572 0.4572)
			(layers "F.Cu" "F.Mask" "F.Paste")
			(net "Net_1642")
		)
		(pad "AR4" smd circle
			(at -19.949922 9.500108)
			(size 0.4572 0.4572)
			(layers "F.Cu" "F.Mask" "F.Paste")
			(net "Net_1626")
		)
		(pad "AR5" smd circle
			(at -18.999962 9.500108)
			(size 0.4572 0.4572)
			(layers "F.Cu" "F.Mask" "F.Paste")
			(net "GND")
		)
		(pad "AR6" smd circle
			(at -18.050002 9.500108)
			(size 0.4572 0.4572)
			(layers "F.Cu" "F.Mask" "F.Paste")
			(net "Net_1373")
		)
		(pad "AR7" smd circle
			(at -17.100042 9.500108)
			(size 0.4572 0.4572)
			(layers "F.Cu" "F.Mask" "F.Paste")
			(net "Net_1714")
		)
		(pad "AR8" smd circle
			(at -16.150082 9.500108)
			(size 0.4572 0.4572)
			(layers "F.Cu" "F.Mask" "F.Paste")
			(net "GND")
		)
		(pad "AR9" smd circle
			(at -15.200122 9.500108)
			(size 0.4572 0.4572)
			(layers "F.Cu" "F.Mask" "F.Paste")
			(net "GND")
		)
		(pad "AR10" smd circle
			(at -14.249908 9.500108)
			(size 0.4572 0.4572)
			(layers "F.Cu" "F.Mask" "F.Paste")
			(net "GND")
		)
		(pad "AR11" smd circle
			(at -13.299948 9.500108)
			(size 0.4572 0.4572)
			(layers "F.Cu" "F.Mask" "F.Paste")
			(net "GND")
		)
		(pad "AR12" smd circle
			(at -12.349988 9.500108)
			(size 0.4572 0.4572)
			(layers "F.Cu" "F.Mask" "F.Paste")
			(net "GND")
		)
		(pad "AR13" smd circle
			(at -11.400028 9.500108)
			(size 0.4572 0.4572)
			(layers "F.Cu" "F.Mask" "F.Paste")
			(net "GND")
		)
		(pad "AR14" smd circle
			(at -10.450068 9.500108)
			(size 0.4572 0.4572)
			(layers "F.Cu" "F.Mask" "F.Paste")
			(net "GND")
		)
		(pad "AR15" smd circle
			(at -9.500108 9.500108)
			(size 0.4572 0.4572)
			(layers "F.Cu" "F.Mask" "F.Paste")
			(net "GND")
		)
		(pad "AR16" smd circle
			(at -8.549894 9.500108)
			(size 0.4572 0.4572)
			(layers "F.Cu" "F.Mask" "F.Paste")
			(net "GND")
		)
		(pad "AR17" smd circle
			(at -7.599934 9.500108)
			(size 0.4572 0.4572)
			(layers "F.Cu" "F.Mask" "F.Paste")
			(net "GND")
		)
		(pad "AR18" smd circle
			(at -6.649974 9.500108)
			(size 0.4572 0.4572)
			(layers "F.Cu" "F.Mask" "F.Paste")
			(net "GND")
		)
		(pad "AR19" smd circle
			(at -5.700014 9.500108)
			(size 0.4572 0.4572)
			(layers "F.Cu" "F.Mask" "F.Paste")
			(net "GND")
		)
		(pad "AR20" smd circle
			(at -4.750054 9.500108)
			(size 0.4572 0.4572)
			(layers "F.Cu" "F.Mask" "F.Paste")
			(net "GND")
		)
		(pad "AR21" smd circle
			(at -3.800094 9.500108)
			(size 0.4572 0.4572)
			(layers "F.Cu" "F.Mask" "F.Paste")
			(net "GND")
		)
		(pad "AR22" smd circle
			(at -2.84988 9.500108)
			(size 0.4572 0.4572)
			(layers "F.Cu" "F.Mask" "F.Paste")
			(net "GND")
		)
		(pad "AR23" smd circle
			(at -1.89992 9.500108)
			(size 0.4572 0.4572)
			(layers "F.Cu" "F.Mask" "F.Paste")
			(net "GND")
		)
		(pad "AR24" smd circle
			(at -0.94996 9.500108)
			(size 0.4572 0.4572)
			(layers "F.Cu" "F.Mask" "F.Paste")
			(net "GND")
		)
		(pad "AR25" smd circle
			(at 0 9.500108)
			(size 0.4572 0.4572)
			(layers "F.Cu" "F.Mask" "F.Paste")
			(net "GND")
		)
		(pad "AR26" smd circle
			(at 0.94996 9.500108)
			(size 0.4572 0.4572)
			(layers "F.Cu" "F.Mask" "F.Paste")
			(net "GND")
		)
		(pad "AR27" smd circle
			(at 1.89992 9.500108)
			(size 0.4572 0.4572)
			(layers "F.Cu" "F.Mask" "F.Paste")
			(net "GND")
		)
		(pad "AR28" smd circle
			(at 2.84988 9.500108)
			(size 0.4572 0.4572)
			(layers "F.Cu" "F.Mask" "F.Paste")
			(net "GND")
		)
		(pad "AR29" smd circle
			(at 3.800094 9.500108)
			(size 0.4572 0.4572)
			(layers "F.Cu" "F.Mask" "F.Paste")
			(net "GND")
		)
		(pad "AR30" smd circle
			(at 4.750054 9.500108)
			(size 0.4572 0.4572)
			(layers "F.Cu" "F.Mask" "F.Paste")
			(net "GND")
		)
		(pad "AR31" smd circle
			(at 5.700014 9.500108)
			(size 0.4572 0.4572)
			(layers "F.Cu" "F.Mask" "F.Paste")
			(net "GND")
		)
		(pad "AR32" smd circle
			(at 6.649974 9.500108)
			(size 0.4572 0.4572)
			(layers "F.Cu" "F.Mask" "F.Paste")
			(net "GND")
		)
		(pad "AR33" smd circle
			(at 7.599934 9.500108)
			(size 0.4572 0.4572)
			(layers "F.Cu" "F.Mask" "F.Paste")
			(net "GND")
		)
		(pad "AR34" smd circle
			(at 8.549894 9.500108)
			(size 0.4572 0.4572)
			(layers "F.Cu" "F.Mask" "F.Paste")
			(net "GND")
		)
		(pad "AR35" smd circle
			(at 9.500108 9.500108)
			(size 0.4572 0.4572)
			(layers "F.Cu" "F.Mask" "F.Paste")
			(net "GND")
		)
		(pad "AR36" smd circle
			(at 10.450068 9.500108)
			(size 0.4572 0.4572)
			(layers "F.Cu" "F.Mask" "F.Paste")
			(net "Net_514")
		)
		(pad "AR37" smd circle
			(at 11.400028 9.500108)
			(size 0.4572 0.4572)
			(layers "F.Cu" "F.Mask" "F.Paste")
			(net "GND")
		)
		(pad "AR38" smd circle
			(at 12.349988 9.500108)
			(size 0.4572 0.4572)
			(layers "F.Cu" "F.Mask" "F.Paste")
			(net "Net_5385")
		)
		(pad "AR39" smd circle
			(at 13.299948 9.500108)
			(size 0.4572 0.4572)
			(layers "F.Cu" "F.Mask" "F.Paste")
			(net "Net_5387")
		)
		(pad "AR40" smd circle
			(at 14.249908 9.500108)
			(size 0.4572 0.4572)
			(layers "F.Cu" "F.Mask" "F.Paste")
			(net "GND")
		)
		(pad "AR41" smd circle
			(at 15.200122 9.500108)
			(size 0.4572 0.4572)
			(layers "F.Cu" "F.Mask" "F.Paste")
			(net "GND")
		)
		(pad "AR42" smd circle
			(at 16.150082 9.500108)
			(size 0.4572 0.4572)
			(layers "F.Cu" "F.Mask" "F.Paste")
			(net "GND")
		)
		(pad "AR43" smd circle
			(at 17.100042 9.500108)
			(size 0.4572 0.4572)
			(layers "F.Cu" "F.Mask" "F.Paste")
			(net "P5E_PEX2_STN0_TX_DP<2>")
		)
		(pad "AR44" smd circle
			(at 18.050002 9.500108)
			(size 0.4572 0.4572)
			(layers "F.Cu" "F.Mask" "F.Paste")
			(net "P5E_PEX2_STN0_TX_DN<2>")
		)
		(pad "AR45" smd circle
			(at 18.999962 9.500108)
			(size 0.4572 0.4572)
			(layers "F.Cu" "F.Mask" "F.Paste")
			(net "GND")
		)
		(pad "AR46" smd circle
			(at 19.949922 9.500108)
			(size 0.4572 0.4572)
			(layers "F.Cu" "F.Mask" "F.Paste")
			(net "P5E_PEX2_STN0_RX_DP<2>")
		)
		(pad "AR47" smd circle
			(at 20.899882 9.500108)
			(size 0.4572 0.4572)
			(layers "F.Cu" "F.Mask" "F.Paste")
			(net "P5E_PEX2_STN0_RX_DN<2>")
		)
		(pad "AR48" smd circle
			(at 21.850096 9.500108)
			(size 0.4572 0.4572)
			(layers "F.Cu" "F.Mask" "F.Paste")
			(net "GND")
		)
		(pad "AR49" smd circle
			(at 22.800056 9.500108)
			(size 0.4572 0.4572)
			(layers "F.Cu" "F.Mask" "F.Paste")
			(net "GND")
		)
		(pad "AT1" smd circle
			(at -22.800056 10.450068)
			(size 0.4572 0.4572)
			(layers "F.Cu" "F.Mask" "F.Paste")
			(net "Net_1578")
		)
		(pad "AT2" smd circle
			(at -21.850096 10.450068)
			(size 0.4572 0.4572)
			(layers "F.Cu" "F.Mask" "F.Paste")
			(net "Net_1570")
		)
		(pad "AT3" smd circle
			(at -20.899882 10.450068)
			(size 0.4572 0.4572)
			(layers "F.Cu" "F.Mask" "F.Paste")
			(net "GND")
		)
		(pad "AT4" smd circle
			(at -19.949922 10.450068)
			(size 0.4572 0.4572)
			(layers "F.Cu" "F.Mask" "F.Paste")
			(net "GND")
		)
		(pad "AT5" smd circle
			(at -18.999962 10.450068)
			(size 0.4572 0.4572)
			(layers "F.Cu" "F.Mask" "F.Paste")
			(net "GND")
		)
		(pad "AT6" smd circle
			(at -18.050002 10.450068)
			(size 0.4572 0.4572)
			(layers "F.Cu" "F.Mask" "F.Paste")
			(net "GND")
		)
		(pad "AT7" smd circle
			(at -17.100042 10.450068)
			(size 0.4572 0.4572)
			(layers "F.Cu" "F.Mask" "F.Paste")
			(net "GND")
		)
		(pad "AT8" smd circle
			(at -16.150082 10.450068)
			(size 0.4572 0.4572)
			(layers "F.Cu" "F.Mask" "F.Paste")
			(net "Net_1718")
		)
		(pad "AT9" smd circle
			(at -15.200122 10.450068)
			(size 0.4572 0.4572)
			(layers "F.Cu" "F.Mask" "F.Paste")
			(net "Net_1414")
		)
		(pad "AT10" smd circle
			(at -14.249908 10.450068)
			(size 0.4572 0.4572)
			(layers "F.Cu" "F.Mask" "F.Paste")
			(net "GND")
		)
		(pad "AT11" smd circle
			(at -13.299948 10.450068)
			(size 0.4572 0.4572)
			(layers "F.Cu" "F.Mask" "F.Paste")
			(net "GND")
		)
		(pad "AT12" smd circle
			(at -12.349988 10.450068)
			(size 0.4572 0.4572)
			(layers "F.Cu" "F.Mask" "F.Paste")
			(net "GND")
		)
		(pad "AT13" smd circle
			(at -11.400028 10.450068)
			(size 0.4572 0.4572)
			(layers "F.Cu" "F.Mask" "F.Paste")
			(net "GND")
		)
		(pad "AT14" smd circle
			(at -10.450068 10.450068)
			(size 0.4572 0.4572)
			(layers "F.Cu" "F.Mask" "F.Paste")
			(net "GND")
		)
		(pad "AT15" smd circle
			(at -9.500108 10.450068)
			(size 0.4572 0.4572)
			(layers "F.Cu" "F.Mask" "F.Paste")
			(net "GND")
		)
		(pad "AT16" smd circle
			(at -8.549894 10.450068)
			(size 0.4572 0.4572)
			(layers "F.Cu" "F.Mask" "F.Paste")
			(net "GND")
		)
		(pad "AT17" smd circle
			(at -7.599934 10.450068)
			(size 0.4572 0.4572)
			(layers "F.Cu" "F.Mask" "F.Paste")
			(net "GND")
		)
		(pad "AT18" smd circle
			(at -6.649974 10.450068)
			(size 0.4572 0.4572)
			(layers "F.Cu" "F.Mask" "F.Paste")
			(net "GND")
		)
		(pad "AT19" smd circle
			(at -5.700014 10.450068)
			(size 0.4572 0.4572)
			(layers "F.Cu" "F.Mask" "F.Paste")
			(net "GND")
		)
		(pad "AT20" smd circle
			(at -4.750054 10.450068)
			(size 0.4572 0.4572)
			(layers "F.Cu" "F.Mask" "F.Paste")
			(net "GND")
		)
		(pad "AT21" smd circle
			(at -3.800094 10.450068)
			(size 0.4572 0.4572)
			(layers "F.Cu" "F.Mask" "F.Paste")
			(net "GND")
		)
		(pad "AT22" smd circle
			(at -2.84988 10.450068)
			(size 0.4572 0.4572)
			(layers "F.Cu" "F.Mask" "F.Paste")
			(net "GND")
		)
		(pad "AT23" smd circle
			(at -1.89992 10.450068)
			(size 0.4572 0.4572)
			(layers "F.Cu" "F.Mask" "F.Paste")
			(net "GND")
		)
		(pad "AT24" smd circle
			(at -0.94996 10.450068)
			(size 0.4572 0.4572)
			(layers "F.Cu" "F.Mask" "F.Paste")
			(net "GND")
		)
		(pad "AT25" smd circle
			(at 0 10.450068)
			(size 0.4572 0.4572)
			(layers "F.Cu" "F.Mask" "F.Paste")
			(net "GND")
		)
		(pad "AT26" smd circle
			(at 0.94996 10.450068)
			(size 0.4572 0.4572)
			(layers "F.Cu" "F.Mask" "F.Paste")
			(net "GND")
		)
		(pad "AT27" smd circle
			(at 1.89992 10.450068)
			(size 0.4572 0.4572)
			(layers "F.Cu" "F.Mask" "F.Paste")
			(net "GND")
		)
		(pad "AT28" smd circle
			(at 2.84988 10.450068)
			(size 0.4572 0.4572)
			(layers "F.Cu" "F.Mask" "F.Paste")
			(net "GND")
		)
		(pad "AT29" smd circle
			(at 3.800094 10.450068)
			(size 0.4572 0.4572)
			(layers "F.Cu" "F.Mask" "F.Paste")
			(net "GND")
		)
		(pad "AT30" smd circle
			(at 4.750054 10.450068)
			(size 0.4572 0.4572)
			(layers "F.Cu" "F.Mask" "F.Paste")
			(net "GND")
		)
		(pad "AT31" smd circle
			(at 5.700014 10.450068)
			(size 0.4572 0.4572)
			(layers "F.Cu" "F.Mask" "F.Paste")
			(net "GND")
		)
		(pad "AT32" smd circle
			(at 6.649974 10.450068)
			(size 0.4572 0.4572)
			(layers "F.Cu" "F.Mask" "F.Paste")
			(net "GND")
		)
		(pad "AT33" smd circle
			(at 7.599934 10.450068)
			(size 0.4572 0.4572)
			(layers "F.Cu" "F.Mask" "F.Paste")
			(net "GND")
		)
		(pad "AT34" smd circle
			(at 8.549894 10.450068)
			(size 0.4572 0.4572)
			(layers "F.Cu" "F.Mask" "F.Paste")
			(net "GND")
		)
		(pad "AT35" smd circle
			(at 9.500108 10.450068)
			(size 0.4572 0.4572)
			(layers "F.Cu" "F.Mask" "F.Paste")
			(net "GND")
		)
		(pad "AT36" smd circle
			(at 10.450068 10.450068)
			(size 0.4572 0.4572)
			(layers "F.Cu" "F.Mask" "F.Paste")
			(net "Net_515")
		)
		(pad "AT37" smd circle
			(at 11.400028 10.450068)
			(size 0.4572 0.4572)
			(layers "F.Cu" "F.Mask" "F.Paste")
			(net "GND")
		)
		(pad "AT38" smd circle
			(at 12.349988 10.450068)
			(size 0.4572 0.4572)
			(layers "F.Cu" "F.Mask" "F.Paste")
			(net "Net_5351")
		)
		(pad "AT39" smd circle
			(at 13.299948 10.450068)
			(size 0.4572 0.4572)
			(layers "F.Cu" "F.Mask" "F.Paste")
			(net "Net_5336")
		)
		(pad "AT40" smd circle
			(at 14.249908 10.450068)
			(size 0.4572 0.4572)
			(layers "F.Cu" "F.Mask" "F.Paste")
			(net "GND")
		)
		(pad "AT41" smd circle
			(at 15.200122 10.450068)
			(size 0.4572 0.4572)
			(layers "F.Cu" "F.Mask" "F.Paste")
			(net "P5E_PEX2_STN0_TX_DP<3>")
		)
		(pad "AT42" smd circle
			(at 16.150082 10.450068)
			(size 0.4572 0.4572)
			(layers "F.Cu" "F.Mask" "F.Paste")
			(net "P5E_PEX2_STN0_TX_DN<3>")
		)
		(pad "AT43" smd circle
			(at 17.100042 10.450068)
			(size 0.4572 0.4572)
			(layers "F.Cu" "F.Mask" "F.Paste")
			(net "GND")
		)
		(pad "AT44" smd circle
			(at 18.050002 10.450068)
			(size 0.4572 0.4572)
			(layers "F.Cu" "F.Mask" "F.Paste")
			(net "GND")
		)
		(pad "AT45" smd circle
			(at 18.999962 10.450068)
			(size 0.4572 0.4572)
			(layers "F.Cu" "F.Mask" "F.Paste")
			(net "GND")
		)
		(pad "AT46" smd circle
			(at 19.949922 10.450068)
			(size 0.4572 0.4572)
			(layers "F.Cu" "F.Mask" "F.Paste")
			(net "GND")
		)
		(pad "AT47" smd circle
			(at 20.899882 10.450068)
			(size 0.4572 0.4572)
			(layers "F.Cu" "F.Mask" "F.Paste")
			(net "GND")
		)
		(pad "AT48" smd circle
			(at 21.850096 10.450068)
			(size 0.4572 0.4572)
			(layers "F.Cu" "F.Mask" "F.Paste")
			(net "P5E_PEX2_STN0_RX_DP<3>")
		)
		(pad "AT49" smd circle
			(at 22.800056 10.450068)
			(size 0.4572 0.4572)
			(layers "F.Cu" "F.Mask" "F.Paste")
			(net "P5E_PEX2_STN0_RX_DN<3>")
		)
		(pad "AU1" smd circle
			(at -22.800056 11.400028)
			(size 0.4572 0.4572)
			(layers "F.Cu" "F.Mask" "F.Paste")
			(net "GND")
		)
		(pad "AU2" smd circle
			(at -21.850096 11.400028)
			(size 0.4572 0.4572)
			(layers "F.Cu" "F.Mask" "F.Paste")
			(net "GND")
		)
		(pad "AU3" smd circle
			(at -20.899882 11.400028)
			(size 0.4572 0.4572)
			(layers "F.Cu" "F.Mask" "F.Paste")
			(net "Net_1602")
		)
		(pad "AU4" smd circle
			(at -19.949922 11.400028)
			(size 0.4572 0.4572)
			(layers "F.Cu" "F.Mask" "F.Paste")
			(net "Net_1614")
		)
	)
)
